# BASEBOARD_FAB2 (Tioga Pass) — schematic netlist excerpt (pin names and nets, part order shuffled) for the footprints in the layout excerpt that follows; sources: Cadence DE-HDL packaged netlist, KiCad conversion of Wiwynn_Tioga_Pass_MB.brd

C2U13  CAP  0.22UF 16V 10% X7R  pkg 0402  page 107 : A = P3E_CPU0_PE1_PCH_RXP<5> ; B = P3E_CPU0_PE1_SS_RXP<5>
R3N9  RES  10.0 1% CHIP  pkg 0402  page 118 : A = H_PM_SYNC1_GTL_R ; B = H_PM_SYNC_GTL
R3T14  RES  10.0K 1% CHIP  pkg 0402  page 136 : A = FM_BIOS_USB_RECOVERY ; B = GND

(kicad_pcb
	(version 20260206)
	(generator "pcbnew")
	(generator_version "10.0")
	(general
		(thickness 1.6)
		(legacy_teardrops no)
	)
	(paper "A4")
	(title_block
		(title "Wiwynn_Tioga_Pass_MB.brd")
		(comment 1 "Tioga Pass / footprints 2890-2892 of 4770")
	)
	(layers
		(0 "F.Cu" signal "TOP")
		(4 "In1.Cu" signal "L2GND")
		(6 "In2.Cu" signal "L3")
		(8 "In3.Cu" signal "L4GND")
		(10 "In4.Cu" signal "L5")
		(12 "In5.Cu" signal "L6GND")
		(14 "In6.Cu" signal "L7VCC")
		(16 "In7.Cu" signal "L8VCC")
		(18 "In8.Cu" signal "L9GND")
		(20 "In9.Cu" signal "L10")
		(22 "In10.Cu" signal "L11GND")
		(24 "In11.Cu" signal "L12")
		(26 "In12.Cu" signal "L13GND")
		(2 "B.Cu" signal "BOTTOM")
		(9 "F.Adhes" user "F.Adhesive")
		(11 "B.Adhes" user "B.Adhesive")
		(13 "F.Paste" user "Package Geometry/Pastemask Top")
		(15 "B.Paste" user "Package Geometry/Pastemask Bottom")
		(5 "F.SilkS" user "Ref Des/Silkscreen Top")
		(7 "B.SilkS" user "Ref Des/Silkscreen Bottom")
		(1 "F.Mask" user "Board Geometry/Soldermask Top")
		(3 "B.Mask" user "Board Geometry/Soldermask Bottom")
		(17 "Dwgs.User" user "User.Drawings")
		(19 "Cmts.User" user "User.Comments")
		(21 "Eco1.User" user "User.Eco1")
		(23 "Eco2.User" user "User.Eco2")
		(25 "Edge.Cuts" user "Board Geometry/Outline")
		(27 "Margin" user)
		(31 "F.CrtYd" user "Package Geometry/Place Bound Top")
		(29 "B.CrtYd" user "Package Geometry/Place Bound Bottom")
		(35 "F.Fab" user "Ref Des/Assembly Top")
		(33 "B.Fab" user "Ref Des/Assembly Bottom")
	)
	(footprint ""
		(layer "B.Cu")
		(at 368.7064 -5.3467 180)
		(property "Reference" "R3T14"
			(at 0 0 0)
			(layer "B.SilkS")
			(hide yes)
			(effects
				(font
					(size 1.27 1.27)
				)
				(justify mirror)
			)
		)
		(property "Value" ""
			(at 0 0 0)
			(layer "B.Fab")
			(effects
				(font
					(size 1.27 1.27)
				)
				(justify mirror)
			)
		)
		(duplicate_pad_numbers_are_jumpers no)
		(fp_poly
			(pts
				(xy 0.2794 -0.1016) (xy -0.2794 -0.1016) (xy -0.2794 0.9906) (xy 0.2794 0.9906)
			)
			(stroke
				(width 0)
				(type default)
			)
			(fill no)
			(layer "B.CrtYd")
		)
		(fp_line
			(start 0.2794 0.9906)
			(end -0.2794 0.9906)
			(stroke
				(width 0.1)
				(type default)
			)
			(layer "B.Fab")
		)
		(fp_line
			(start 0.2794 -0.1016)
			(end 0.2794 0.9906)
			(stroke
				(width 0.1)
				(type default)
			)
			(layer "B.Fab")
		)
		(fp_line
			(start -0.2794 0.9906)
			(end -0.2794 -0.1016)
			(stroke
				(width 0.1)
				(type default)
			)
			(layer "B.Fab")
		)
		(fp_line
			(start -0.2794 -0.1016)
			(end 0.2794 -0.1016)
			(stroke
				(width 0.1)
				(type default)
			)
			(layer "B.Fab")
		)
		(pad "1" smd rect
			(at 0 0)
			(size 0.508 0.508)
			(layers "B.Cu" "B.Mask" "B.Paste")
			(net "FM_BIOS_USB_RECOVERY")
		)
		(pad "2" smd rect
			(at 0 0.889)
			(size 0.508 0.508)
			(layers "B.Cu" "B.Mask" "B.Paste")
			(net "GND")
		)
		(zone
			(layer "B.Cu")
			(hatch none 0.5)
			(connect_pads
				(clearance 0)
			)
			(min_thickness 0.25)
			(keepout
				(tracks not_allowed)
				(vias allowed)
				(pads allowed)
				(copperpour not_allowed)
				(footprints allowed)
			)
			(placement
				(enabled no)
				(sheetname "")
			)
			(fill
				(thermal_gap 0.5)
				(thermal_bridge_width 0.5)
				(island_removal_mode 0)
			)
			(polygon
				(pts
					(xy 368.4524 -5.9817) (xy 368.9604 -5.9817) (xy 368.9604 -5.6007) (xy 368.4524 -5.6007)
				)
			)
		)
		(zone
			(layer "B.Cu")
			(hatch none 0.5)
			(connect_pads
				(clearance 0)
			)
			(min_thickness 0.25)
			(keepout
				(tracks allowed)
				(vias not_allowed)
				(pads allowed)
				(copperpour not_allowed)
				(footprints allowed)
			)
			(placement
				(enabled no)
				(sheetname "")
			)
			(fill
				(thermal_gap 0.5)
				(thermal_bridge_width 0.5)
				(island_removal_mode 0)
			)
			(polygon
				(pts
					(xy 368.4524 -5.6007) (xy 368.9604 -5.6007) (xy 368.9604 -5.9817) (xy 368.4524 -5.9817)
				)
			)
		)
	)
	(footprint ""
		(layer "B.Cu")
		(at 347.316806 -61.257434)
		(property "Reference" "C2U13"
			(at 0 0 0)
			(layer "B.SilkS")
			(hide yes)
			(effects
				(font
					(size 1.27 1.27)
				)
				(justify mirror)
			)
		)
		(property "Value" ""
			(at 0 0 0)
			(layer "B.Fab")
			(effects
				(font
					(size 1.27 1.27)
				)
				(justify mirror)
			)
		)
		(duplicate_pad_numbers_are_jumpers no)
		(fp_poly
			(pts
				(xy -0.3048 -0.1016) (xy -0.3048 0.9906) (xy 0.3048 0.9906) (xy 0.3048 -0.1016)
			)
			(stroke
				(width 0)
				(type default)
			)
			(fill no)
			(layer "B.CrtYd")
		)
		(fp_line
			(start -0.3048 -0.1016)
			(end 0.3048 -0.1016)
			(stroke
				(width 0.1)
				(type default)
			)
			(layer "B.Fab")
		)
		(fp_line
			(start -0.3048 0.9906)
			(end -0.3048 -0.1016)
			(stroke
				(width 0.1)
				(type default)
			)
			(layer "B.Fab")
		)
		(fp_line
			(start 0.3048 -0.1016)
			(end 0.3048 0.9906)
			(stroke
				(width 0.1)
				(type default)
			)
			(layer "B.Fab")
		)
		(fp_line
			(start 0.3048 0.9906)
			(end -0.3048 0.9906)
			(stroke
				(width 0.1)
				(type default)
			)
			(layer "B.Fab")
		)
		(pad "1" smd rect
			(at 0 0 180)
			(size 0.508 0.508)
			(layers "B.Cu" "B.Mask" "B.Paste")
			(net "P3E_CPU0_PE1_PCH_RXP<5>")
		)
		(pad "2" smd rect
			(at 0 0.889 180)
			(size 0.508 0.508)
			(layers "B.Cu" "B.Mask" "B.Paste")
			(net "P3E_CPU0_PE1_SS_RXP<5>")
		)
		(zone
			(layer "B.Cu")
			(hatch none 0.5)
			(connect_pads
				(clearance 0)
			)
			(min_thickness 0.25)
			(keepout
				(tracks allowed)
				(vias not_allowed)
				(pads allowed)
				(copperpour not_allowed)
				(footprints allowed)
			)
			(placement
				(enabled no)
				(sheetname "")
			)
			(fill
				(thermal_gap 0.5)
				(thermal_bridge_width 0.5)
				(island_removal_mode 0)
			)
			(polygon
				(pts
					(xy 347.570806 -61.003434) (xy 347.062806 -61.003434) (xy 347.062806 -60.622434) (xy 347.570806 -60.622434)
				)
			)
		)
	)
	(footprint ""
		(layer "B.Cu")
		(at 375.285 -89.4715)
		(property "Reference" "R3N9"
			(at 0.8382 -0.67818 0)
			(unlocked yes)
			(layer "B.SilkS")
			(effects
				(font
					(size 0.4064 0.254)
					(thickness 0.1524)
				)
				(justify left mirror)
			)
		)
		(property "Value" ""
			(at 0 0 0)
			(layer "B.Fab")
			(effects
				(font
					(size 1.27 1.27)
				)
				(justify mirror)
			)
		)
		(duplicate_pad_numbers_are_jumpers no)
		(fp_poly
			(pts
				(xy 0.2794 -0.1016) (xy -0.2794 -0.1016) (xy -0.2794 0.9906) (xy 0.2794 0.9906)
			)
			(stroke
				(width 0)
				(type default)
			)
			(fill no)
			(layer "B.CrtYd")
		)
		(fp_line
			(start -0.2794 -0.1016)
			(end 0.2794 -0.1016)
			(stroke
				(width 0.1)
				(type default)
			)
			(layer "B.Fab")
		)
		(fp_line
			(start -0.2794 0.9906)
			(end -0.2794 -0.1016)
			(stroke
				(width 0.1)
				(type default)
			)
			(layer "B.Fab")
		)
		(fp_line
			(start 0.2794 -0.1016)
			(end 0.2794 0.9906)
			(stroke
				(width 0.1)
				(type default)
			)
			(layer "B.Fab")
		)
		(fp_line
			(start 0.2794 0.9906)
			(end -0.2794 0.9906)
			(stroke
				(width 0.1)
				(type default)
			)
			(layer "B.Fab")
		)
		(pad "1" smd rect
			(at 0 0 180)
			(size 0.508 0.508)
			(layers "B.Cu" "B.Mask" "B.Paste")
			(net "H_PM_SYNC1_GTL_R")
		)
		(pad "2" smd rect
			(at 0 0.889 180)
			(size 0.508 0.508)
			(layers "B.Cu" "B.Mask" "B.Paste")
			(net "H_PM_SYNC_GTL")
		)
		(zone
			(layer "B.Cu")
			(hatch none 0.5)
			(connect_pads
				(clearance 0)
			)
			(min_thickness 0.25)
			(keepout
				(tracks allowed)
				(vias not_allowed)
				(pads allowed)
				(copperpour not_allowed)
				(footprints allowed)
			)
			(placement
				(enabled no)
				(sheetname "")
			)
			(fill
				(thermal_gap 0.5)
				(thermal_bridge_width 0.5)
				(island_removal_mode 0)
			)
			(polygon
				(pts
					(xy 375.539 -89.2175) (xy 375.031 -89.2175) (xy 375.031 -88.8365) (xy 375.539 -88.8365)
				)
			)
		)
		(zone
			(layer "B.Cu")
			(hatch none 0.5)
			(connect_pads
				(clearance 0)
			)
			(min_thickness 0.25)
			(keepout
				(tracks not_allowed)
				(vias allowed)
				(pads allowed)
				(copperpour not_allowed)
				(footprints allowed)
			)
			(placement
				(enabled no)
				(sheetname "")
			)
			(fill
				(thermal_gap 0.5)
				(thermal_bridge_width 0.5)
				(island_removal_mode 0)
			)
			(polygon
				(pts
					(xy 375.539 -88.8365) (xy 375.031 -88.8365) (xy 375.031 -89.2175) (xy 375.539 -89.2175)
				)
			)
		)
	)
)
